# T6G (Grand Teton) — schematic parts with pin connectivity, parts 8082–8082 of 8303; source: Cadence DE-HDL packaged netlist (pstxprt.dat, pstxnet.dat, pstchip.dat)

U26  GENOA_SP5  SOCKET6096_13568-001 IO  pkg SOCKET6096_93-4X120-45XA  page 37  (pins 5713-6048 of 6096)
  R52  G1_RXN14  IN  = P5E_CPU1_G1_RX_DN<14>
  R53  G1_RXP14  IN  = P5E_CPU1_G1_RX_DP<14>
  R54  VSS_R54  POWER  = GND
  R55  MCA_DQS_H6  BI  = M_C_CPU1_SA_DQS_DP<6>
  R56  VSS_R56  POWER  = GND
  R57  MCA_DATA12  BI  = M_C_CPU1_SA_DQ<12>
  R58  VSS_R58  POWER  = GND
  R59  MDA_DQS_H6  BI  = M_D_CPU1_SA_DQS_DP<6>
  R60  MDA_DATA12  BI  = M_D_CPU1_SA_DQ<12>
  R61  VSS_R61  POWER  = GND
  R62  MBA_DQS_H6  BI  = M_B_CPU1_SA_DQS_DP<6>
  R63  VSS_R63  POWER  = GND
  R64  MBA_DATA12  BI  = M_B_CPU1_SA_DQ<12>
  R65  VSS_R65  POWER  = GND
  R66  MFA_DQS_H6  BI  = M_F_CPU1_SA_DQS_DP<6>
  R67  MFA_DATA12  BI  = M_F_CPU1_SA_DQ<12>
  R68  VSS_R68  POWER  = GND
  R69  MEA_DQS_H6  BI  = M_E_CPU1_SA_DQS_DP<6>
  R70  VSS_R70  POWER  = GND
  R71  MEA_DATA12  BI  = M_E_CPU1_SA_DQ<12>
  R72  VSS_R72  POWER  = GND
  R73  MAA_DQS_H6  BI  = M_A_CPU1_SA_DQS_DP<6>
  R74  MAA_DATA12  BI  = M_A_CPU1_SA_DQ<12>
  R75  VSS_R75  POWER  = GND
  T2  MGA_DATA14  BI  = M_G_CPU1_SA_DQ<14>
  T3  VSS_T3  POWER  = GND
  T4  MGA_DATA13  BI  = M_G_CPU1_SA_DQ<13>
  T5  VSS_T5  POWER  = GND
  T6  MKA_DATA14  BI  = M_K_CPU1_SA_DQ<14>
  T7  MKA_DATA13  BI  = M_K_CPU1_SA_DQ<13>
  T8  VSS_T8  POWER  = GND
  T9  MLA_DATA14  BI  = M_L_CPU1_SA_DQ<14>
  T10  VSS_T10  POWER  = GND
  T11  MLA_DATA13  BI  = M_L_CPU1_SA_DQ<13>
  T12  VSS_T12  POWER  = GND
  T13  MHA_DATA14  BI  = M_H_CPU1_SA_DQ<14>
  T14  MHA_DATA13  BI  = M_H_CPU1_SA_DQ<13>
  T15  VSS_T15  POWER  = GND
  T16  MJA_DATA14  BI  = M_J_CPU1_SA_DQ<14>
  T17  VSS_T17  POWER  = GND
  T18  MJA_DATA13  BI  = M_J_CPU1_SA_DQ<13>
  T19  VSS_T19  POWER  = GND
  T20  MIA_DATA14  BI  = M_I_CPU1_SA_DQ<14>
  T21  MIA_DATA13  BI  = M_I_CPU1_SA_DQ<13>
  T22  VSS_T22  POWER  = GND
  T23  VDDCR_CPU0_T23  POWER  = PVDDCR_CPU0_P1
  T24  VDDCR_CPU0_T24  POWER  = PVDDCR_CPU0_P1
  T25  VSS_T25  POWER  = GND
  T26  VDDCR_CPU0_T26  POWER  = PVDDCR_CPU0_P1
  T27  VDDCR_CPU0_T27  POWER  = PVDDCR_CPU0_P1
  T28  VSS_T28  POWER  = GND
  T29  VDDCR_CPU0_T29  POWER  = PVDDCR_CPU0_P1
  T30  VDDCR_CPU0_T30  POWER  = PVDDCR_CPU0_P1
  T31  VSS_T31  POWER  = GND
  T32  VDDCR_CPU0_T32  POWER  = PVDDCR_CPU0_P1
  T33  VDDCR_CPU0_T33  POWER  = PVDDCR_CPU0_P1
  T34  VSS_T34  POWER  = GND
  T35  \g3_txp14||sata36_txp\  OUT  = GMI_CPU1_G3_CPU0_G1_TX_DP<1>
  T36  \g3_txn14||sata36_txn\  OUT  = GMI_CPU1_G3_CPU0_G1_TX_DN<1>
  T37  VSS_T37  POWER  = GND
  T39  VSS_T39  POWER  = GND
  T40  G1_RXN1  IN  = P5E_CPU1_G1_RX_DN<1>
  T41  G1_RXP1  IN  = P5E_CPU1_G1_RX_DP<1>
  T42  VSS_T42  POWER  = GND
  T43  VDDCR_CPU0_T43  POWER  = PVDDCR_CPU0_P1
  T44  VDDCR_CPU0_T44  POWER  = PVDDCR_CPU0_P1
  T45  VSS_T45  POWER  = GND
  T46  VDDCR_CPU0_T46  POWER  = PVDDCR_CPU0_P1
  T47  VDDCR_CPU0_T47  POWER  = PVDDCR_CPU0_P1
  T48  VSS_T48  POWER  = GND
  T49  VDDCR_CPU0_T49  POWER  = PVDDCR_CPU0_P1
  T50  VDDCR_CPU0_T50  POWER  = PVDDCR_CPU0_P1
  T51  VSS_T51  POWER  = GND
  T52  VDDCR_CPU0_T52  POWER  = PVDDCR_CPU0_P1
  T53  VDDCR_CPU0_T53  POWER  = PVDDCR_CPU0_P1
  T54  VSS_T54  POWER  = GND
  T55  MCA_DATA13  BI  = M_C_CPU1_SA_DQ<13>
  T56  MCA_DATA14  BI  = M_C_CPU1_SA_DQ<14>
  T57  VSS_T57  POWER  = GND
  T58  MDA_DATA13  BI  = M_D_CPU1_SA_DQ<13>
  T59  VSS_T59  POWER  = GND
  T60  MDA_DATA14  BI  = M_D_CPU1_SA_DQ<14>
  T61  VSS_T61  POWER  = GND
  T62  MBA_DATA13  BI  = M_B_CPU1_SA_DQ<13>
  T63  MBA_DATA14  BI  = M_B_CPU1_SA_DQ<14>
  T64  VSS_T64  POWER  = GND
  T65  MFA_DATA13  BI  = M_F_CPU1_SA_DQ<13>
  T66  VSS_T66  POWER  = GND
  T67  MFA_DATA14  BI  = M_F_CPU1_SA_DQ<14>
  T68  VSS_T68  POWER  = GND
  T69  MEA_DATA13  BI  = M_E_CPU1_SA_DQ<13>
  T70  MEA_DATA14  BI  = M_E_CPU1_SA_DQ<14>
  T71  VSS_T71  POWER  = GND
  T72  MAA_DATA13  BI  = M_A_CPU1_SA_DQ<13>
  T73  VSS_T73  POWER  = GND
  T74  MAA_DATA14  BI  = M_A_CPU1_SA_DQ<14>
  U1  VSS_U1  POWER  = GND
  U2  MGA_DATA16  BI  = M_G_CPU1_SA_DQ<16>
  U3  MGA_DATA15  BI  = M_G_CPU1_SA_DQ<15>
  U4  VDDCR_SOC_U4  POWER  = PVDDCR_SOC_P1
  U5  MKA_DATA16  BI  = M_K_CPU1_SA_DQ<16>
  U6  VSS_U6  POWER  = GND
  U7  MKA_DATA15  BI  = M_K_CPU1_SA_DQ<15>
  U8  VSS_U8  POWER  = GND
  U9  MLA_DATA16  BI  = M_L_CPU1_SA_DQ<16>
  U10  MLA_DATA15  BI  = M_L_CPU1_SA_DQ<15>
  U11  VDDCR_SOC_U11  POWER  = PVDDCR_SOC_P1
  U12  MHA_DATA16  BI  = M_H_CPU1_SA_DQ<16>
  U13  VSS_U13  POWER  = GND
  U14  MHA_DATA15  BI  = M_H_CPU1_SA_DQ<15>
  U15  VSS_U15  POWER  = GND
  U16  MJA_DATA16  BI  = M_J_CPU1_SA_DQ<16>
  U17  MJA_DATA15  BI  = M_J_CPU1_SA_DQ<15>
  U18  VDDCR_SOC_U18  POWER  = PVDDCR_SOC_P1
  U19  MIA_DATA16  BI  = M_I_CPU1_SA_DQ<16>
  U20  VSS_U20  POWER  = GND
  U21  MIA_DATA15  BI  = M_I_CPU1_SA_DQ<15>
  U22  VSS_U22  POWER  = GND
  U23  \g3_txp0||sata20_txp\  OUT  = GMI_CPU1_G3_CPU0_G1_TX_DP<15>
  U24  \g3_txn0||sata20_txn\  OUT  = GMI_CPU1_G3_CPU0_G1_TX_DN<15>
  U25  VSS_U25  POWER  = GND
  U26  \g3_txp3||sata23_txp\  OUT  = GMI_CPU1_G3_CPU0_G1_TX_DP<12>
  U27  \g3_txn3||sata23_txn\  OUT  = GMI_CPU1_G3_CPU0_G1_TX_DN<12>
  U28  VSS_U28  POWER  = GND
  U29  \g3_txp9||sata31_txp\  OUT  = GMI_CPU1_G3_CPU0_G1_TX_DP<6>
  U30  \g3_txn9||sata31_txn\  OUT  = GMI_CPU1_G3_CPU0_G1_TX_DN<6>
  U31  VSS_U31  POWER  = GND
  U32  \g3_txp12||sata34_txp\  OUT  = GMI_CPU1_G3_CPU0_G1_TX_DP<3>
  U33  \g3_txn12||sata34_txn\  OUT  = GMI_CPU1_G3_CPU0_G1_TX_DN<3>
  U34  VSS_U34  POWER  = GND
  U35  VDDCR_CPU0_U35  POWER  = PVDDCR_CPU0_P1
  U36  VDDCR_CPU0_U36  POWER  = PVDDCR_CPU0_P1
  U40  VDDCR_CPU0_U40  POWER  = PVDDCR_CPU0_P1
  U41  VDDCR_CPU0_U41  POWER  = PVDDCR_CPU0_P1
  U42  VSS_U42  POWER  = GND
  U43  G1_RXN3  IN  = P5E_CPU1_G1_RX_DN<3>
  U44  G1_RXP3  IN  = P5E_CPU1_G1_RX_DP<3>
  U45  VSS_U45  POWER  = GND
  U46  G1_RXN6  IN  = P5E_CPU1_G1_RX_DN<6>
  U47  G1_RXP6  IN  = P5E_CPU1_G1_RX_DP<6>
  U48  VSS_U48  POWER  = GND
  U49  G1_RXN12  IN  = P5E_CPU1_G1_RX_DN<12>
  U50  G1_RXP12  IN  = P5E_CPU1_G1_RX_DP<12>
  U51  VSS_U51  POWER  = GND
  U52  G1_RXN15  IN  = P5E_CPU1_G1_RX_DN<15>
  U53  G1_RXP15  IN  = P5E_CPU1_G1_RX_DP<15>
  U54  VSS_U54  POWER  = GND
  U55  MCA_DATA15  BI  = M_C_CPU1_SA_DQ<15>
  U56  VSS_U56  POWER  = GND
  U57  MCA_DATA16  BI  = M_C_CPU1_SA_DQ<16>
  U58  VDDIO_U58  POWER  = PVDDIO_P1
  U59  MDA_DATA15  BI  = M_D_CPU1_SA_DQ<15>
  U60  MDA_DATA16  BI  = M_D_CPU1_SA_DQ<16>
  U61  VSS_U61  POWER  = GND
  U62  MBA_DATA15  BI  = M_B_CPU1_SA_DQ<15>
  U63  VSS_U63  POWER  = GND
  U64  MBA_DATA16  BI  = M_B_CPU1_SA_DQ<16>
  U65  VDDIO_U65  POWER  = PVDDIO_P1
  U66  MFA_DATA15  BI  = M_F_CPU1_SA_DQ<15>
  U67  MFA_DATA16  BI  = M_F_CPU1_SA_DQ<16>
  U68  VSS_U68  POWER  = GND
  U69  MEA_DATA15  BI  = M_E_CPU1_SA_DQ<15>
  U70  VSS_U70  POWER  = GND
  U71  MEA_DATA16  BI  = M_E_CPU1_SA_DQ<16>
  U72  VDDIO_U72  POWER  = PVDDIO_P1
  U73  MAA_DATA15  BI  = M_A_CPU1_SA_DQ<15>
  U74  MAA_DATA16  BI  = M_A_CPU1_SA_DQ<16>
  U75  VSS_U75  POWER  = GND
  V2  MGA_DATA18  BI  = M_G_CPU1_SA_DQ<18>
  V3  VSS_V3  POWER  = GND
  V4  MGA_DATA17  BI  = M_G_CPU1_SA_DQ<17>
  V5  VSS_V5  POWER  = GND
  V6  MKA_DATA18  BI  = M_K_CPU1_SA_DQ<18>
  V7  MKA_DATA17  BI  = M_K_CPU1_SA_DQ<17>
  V8  VSS_V8  POWER  = GND
  V9  MLA_DATA18  BI  = M_L_CPU1_SA_DQ<18>
  V10  VSS_V10  POWER  = GND
  V11  MLA_DATA17  BI  = M_L_CPU1_SA_DQ<17>
  V12  VSS_V12  POWER  = GND
  V13  MHA_DATA18  BI  = M_H_CPU1_SA_DQ<18>
  V14  MHA_DATA17  BI  = M_H_CPU1_SA_DQ<17>
  V15  VSS_V15  POWER  = GND
  V16  MJA_DATA18  BI  = M_J_CPU1_SA_DQ<18>
  V17  VSS_V17  POWER  = GND
  V18  MJA_DATA17  BI  = M_J_CPU1_SA_DQ<17>
  V19  VSS_V19  POWER  = GND
  V20  MIA_DATA18  BI  = M_I_CPU1_SA_DQ<18>
  V21  MIA_DATA17  BI  = M_I_CPU1_SA_DQ<17>
  V22  VDDCR_SOC_V22  POWER  = PVDDCR_SOC_P1
  V23  VSS_V23  POWER  = GND
  V24  VSS_V24  POWER  = GND
  V25  VSS_V25  POWER  = GND
  V26  VSS_V26  POWER  = GND
  V27  VSS_V27  POWER  = GND
  V28  VSS_V28  POWER  = GND
  V29  VSS_V29  POWER  = GND
  V30  VSS_V30  POWER  = GND
  V31  VSS_V31  POWER  = GND
  V32  VSS_V32  POWER  = GND
  V33  VSS_V33  POWER  = GND
  V34  VSS_V34  POWER  = GND
  V35  \g3_txp15||sata37_txp\  OUT  = GMI_CPU1_G3_CPU0_G1_TX_DP<0>
  V36  \g3_txn15||sata37_txn\  OUT  = GMI_CPU1_G3_CPU0_G1_TX_DN<0>
  V37  VSS_V37  POWER  = GND
  V39  VSS_V39  POWER  = GND
  V40  G1_RXN0  IN  = P5E_CPU1_G1_RX_DN<0>
  V41  G1_RXP0  IN  = P5E_CPU1_G1_RX_DP<0>
  V42  VSS_V42  POWER  = GND
  V43  VSS_V43  POWER  = GND
  V44  VSS_V44  POWER  = GND
  V45  VSS_V45  POWER  = GND
  V46  VSS_V46  POWER  = GND
  V47  VSS_V47  POWER  = GND
  V48  VSS_V48  POWER  = GND
  V49  VSS_V49  POWER  = GND
  V50  VSS_V50  POWER  = GND
  V51  VSS_V51  POWER  = GND
  V52  VSS_V52  POWER  = GND
  V53  VSS_V53  POWER  = GND
  V54  VDDIO_V54  POWER  = PVDDIO_P1
  V55  MCA_DATA17  BI  = M_C_CPU1_SA_DQ<17>
  V56  MCA_DATA18  BI  = M_C_CPU1_SA_DQ<18>
  V57  VSS_V57  POWER  = GND
  V58  MDA_DATA17  BI  = M_D_CPU1_SA_DQ<17>
  V59  VSS_V59  POWER  = GND
  V60  MDA_DATA18  BI  = M_D_CPU1_SA_DQ<18>
  V61  VSS_V61  POWER  = GND
  V62  MBA_DATA17  BI  = M_B_CPU1_SA_DQ<17>
  V63  MBA_DATA18  BI  = M_B_CPU1_SA_DQ<18>
  V64  VSS_V64  POWER  = GND
  V65  MFA_DATA17  BI  = M_F_CPU1_SA_DQ<17>
  V66  VSS_V66  POWER  = GND
  V67  MFA_DATA18  BI  = M_F_CPU1_SA_DQ<18>
  V68  VSS_V68  POWER  = GND
  V69  MEA_DATA17  BI  = M_E_CPU1_SA_DQ<17>
  V70  MEA_DATA18  BI  = M_E_CPU1_SA_DQ<18>
  V71  VSS_V71  POWER  = GND
  V72  MAA_DATA17  BI  = M_A_CPU1_SA_DQ<17>
  V73  VSS_V73  POWER  = GND
  V74  MAA_DATA18  BI  = M_A_CPU1_SA_DQ<18>
  W1  VSS_W1  POWER  = GND
  W2  MGA_DQS_H2  BI  = M_G_CPU1_SA_DQS_DP<2>
  W3  MGA_DATA19  BI  = M_G_CPU1_SA_DQ<19>
  W4  VSS_W4  POWER  = GND
  W5  MKA_DQS_H2  BI  = M_K_CPU1_SA_DQS_DP<2>
  W6  VSS_W6  POWER  = GND
  W7  MKA_DATA19  BI  = M_K_CPU1_SA_DQ<19>
  W8  VSS_W8  POWER  = GND
  W9  MLA_DQS_H2  BI  = M_L_CPU1_SA_DQS_DP<2>
  W10  MLA_DATA19  BI  = M_L_CPU1_SA_DQ<19>
  W11  VSS_W11  POWER  = GND
  W12  MHA_DQS_H2  BI  = M_H_CPU1_SA_DQS_DP<2>
  W13  VSS_W13  POWER  = GND
  W14  MHA_DATA19  BI  = M_H_CPU1_SA_DQ<19>
  W15  VSS_W15  POWER  = GND
  W16  MJA_DQS_H2  BI  = M_J_CPU1_SA_DQS_DP<2>
  W17  MJA_DATA19  BI  = M_J_CPU1_SA_DQ<19>
  W18  VSS_W18  POWER  = GND
  W19  MIA_DQS_H2  BI  = M_I_CPU1_SA_DQS_DP<2>
  W20  VSS_W20  POWER  = GND
  W21  MIA_DATA19  BI  = M_I_CPU1_SA_DQ<19>
  W22  VSS_W22  POWER  = GND
  W23  \g3_txp2||sata22_txp\  OUT  = GMI_CPU1_G3_CPU0_G1_TX_DP<13>
  W24  \g3_txn2||sata22_txn\  OUT  = GMI_CPU1_G3_CPU0_G1_TX_DN<13>
  W25  VSS_W25  POWER  = GND
  W26  \g3_txp6||sata26_txp\  OUT  = GMI_CPU1_G3_CPU0_G1_TX_DP<9>
  W27  \g3_txn6||sata26_txn\  OUT  = GMI_CPU1_G3_CPU0_G1_TX_DN<9>
  W28  VSS_W28  POWER  = GND
  W29  VDDCR_CPU0_W29  POWER  = PVDDCR_CPU0_P1
  W30  VDDCR_CPU0_W30  POWER  = PVDDCR_CPU0_P1
  W31  TEST41_IOD  TRI  = TP_CPU1_TEST41_IOD
  W32  VDDCR_CPU0_W32  POWER  = PVDDCR_CPU0_P1
  W33  VDDCR_CPU0_W33  POWER  = PVDDCR_CPU0_P1
  W34  VSS_W34  POWER  = GND
  W35  VSS_W35  POWER  = GND
  W36  VSS_W36  POWER  = GND
  W40  VSS_W40  POWER  = GND
  W41  VSS_W41  POWER  = GND
  W42  VSS_W42  POWER  = GND
  W43  VDDCR_CPU0_W43  POWER  = PVDDCR_CPU0_P1
  W44  VDDCR_CPU0_W44  POWER  = PVDDCR_CPU0_P1
  W45  VSS_W45  POWER  = GND
  W46  VDDCR_CPU0_W46  POWER  = PVDDCR_CPU0_P1
  W47  VDDCR_CPU0_W47  POWER  = PVDDCR_CPU0_P1
  W48  VSS_W48  POWER  = GND
  W49  G1_RXN9  IN  = P5E_CPU1_G1_RX_DN<9>
  W50  G1_RXP9  IN  = P5E_CPU1_G1_RX_DP<9>
  W51  VSS_W51  POWER  = GND
  W52  G1_RXN13  IN  = P5E_CPU1_G1_RX_DN<13>
  W53  G1_RXP13  IN  = P5E_CPU1_G1_RX_DP<13>
  W54  VSS_W54  POWER  = GND
  W55  MCA_DATA19  BI  = M_C_CPU1_SA_DQ<19>
  W56  VSS_W56  POWER  = GND
  W57  MCA_DQS_H2  BI  = M_C_CPU1_SA_DQS_DP<2>
  W58  VSS_W58  POWER  = GND
  W59  MDA_DATA19  BI  = M_D_CPU1_SA_DQ<19>
  W60  MDA_DQS_H2  BI  = M_D_CPU1_SA_DQS_DP<2>
  W61  VSS_W61  POWER  = GND
  W62  MBA_DATA19  BI  = M_B_CPU1_SA_DQ<19>
  W63  VSS_W63  POWER  = GND
  W64  MBA_DQS_H2  BI  = M_B_CPU1_SA_DQS_DP<2>
  W65  VSS_W65  POWER  = GND
  W66  MFA_DATA19  BI  = M_F_CPU1_SA_DQ<19>
  W67  MFA_DQS_H2  BI  = M_F_CPU1_SA_DQS_DP<2>
  W68  VSS_W68  POWER  = GND
  W69  MEA_DATA19  BI  = M_E_CPU1_SA_DQ<19>
  W70  VSS_W70  POWER  = GND
  W71  MEA_DQS_H2  BI  = M_E_CPU1_SA_DQS_DP<2>
  W72  VSS_W72  POWER  = GND
  W73  MAA_DATA19  BI  = M_A_CPU1_SA_DQ<19>
  W74  MAA_DQS_H2  BI  = M_A_CPU1_SA_DQS_DP<2>
  W75  VSS_W75  POWER  = GND
  Y2  MGA_DQS_L2  BI  = M_G_CPU1_SA_DQS_DN<2>
  Y3  VSS_Y3  POWER  = GND
  Y4  MGA_DQS_L7  BI  = M_G_CPU1_SA_DQS_DN<7>
  Y5  VDDCR_SOC_Y5  POWER  = PVDDCR_SOC_P1
  Y6  MKA_DQS_L2  BI  = M_K_CPU1_SA_DQS_DN<2>
  Y7  MKA_DQS_L7  BI  = M_K_CPU1_SA_DQS_DN<7>
  Y8  VSS_Y8  POWER  = GND
  Y9  MLA_DQS_L2  BI  = M_L_CPU1_SA_DQS_DN<2>
  Y10  VSS_Y10  POWER  = GND
  Y11  MLA_DQS_L7  BI  = M_L_CPU1_SA_DQS_DN<7>
  Y12  VDDCR_SOC_Y12  POWER  = PVDDCR_SOC_P1
  Y13  MHA_DQS_L2  BI  = M_H_CPU1_SA_DQS_DN<2>
  Y14  MHA_DQS_L7  BI  = M_H_CPU1_SA_DQS_DN<7>
  Y15  VSS_Y15  POWER  = GND
  Y16  MJA_DQS_L2  BI  = M_J_CPU1_SA_DQS_DN<2>
  Y17  VSS_Y17  POWER  = GND
  Y18  MJA_DQS_L7  BI  = M_J_CPU1_SA_DQS_DN<7>
  Y19  VDDCR_SOC_Y19  POWER  = PVDDCR_SOC_P1
  Y20  MIA_DQS_L2  BI  = M_I_CPU1_SA_DQS_DN<2>
  Y21  MIA_DQS_L7  BI  = M_I_CPU1_SA_DQS_DN<7>
  Y22  VSS_Y22  POWER  = GND
  Y23  VSS_Y23  POWER  = GND
  Y24  VSS_Y24  POWER  = GND
  Y25  VSS_Y25  POWER  = GND
